# SCM (Grand Teton) — schematic netlist excerpt (pin names and nets, part order shuffled) for the footprints in the layout excerpt that follows; sources: Cadence DE-HDL packaged netlist, KiCad conversion of 12092022_DA0F0TMDCD0_F0T_Management_Board_D_brd_V3_OCP.brd

R47  Q_RES  33.2 1% CHIP  pkg 0402LF  page 46 : A = SMB_BMC_TPM_MM16_SCL ; B = SMB_BMC_MM16_R5_SCL

J8  SCONN13_502280130CV01  SCONN13_50228-0130C-V01 IO  pkg CON_13S1H2S_P1XA  page 23
  \1\  = V_DACR_IO
  \2\  = GND
  \3\  = V_DACG_IO
  \4\  = GND
  \5\  = V_DACB_IO
  \6\  = GND
  \7\  = V_VGAVS_BUF
  \8\  = GND
  \9\  = V_VGAHS_BUF
  \10\  = GND
  \11\  = V_BMC_LS_DDC_SDA_R
  \12\  = V_BMC_LS_DDC_SCL_R
  \13\  = CRT_VCC5_2_FUSE
  G1  = GND
  G2  = GND

(kicad_pcb
	(version 20260206)
	(generator "pcbnew")
	(generator_version "10.0")
	(general
		(thickness 1.6)
		(legacy_teardrops no)
	)
	(paper "A4")
	(title_block
		(title "12092022_DA0F0TMDCD0_F0T_Management_Board_D_brd_V3_OCP.brd")
		(comment 1 "Grand Teton / footprints 556-557 of 1440")
	)
	(layers
		(0 "F.Cu" signal "TOP")
		(4 "In1.Cu" signal "GND")
		(6 "In2.Cu" signal "IN1")
		(8 "In3.Cu" signal "GND1")
		(10 "In4.Cu" signal "IN2")
		(12 "In5.Cu" signal "VCC")
		(14 "In6.Cu" signal "VCC1")
		(16 "In7.Cu" signal "IN3")
		(18 "In8.Cu" signal "GND2")
		(20 "In9.Cu" signal "IN4")
		(22 "In10.Cu" signal "GND3")
		(2 "B.Cu" signal "BOTTOM")
		(9 "F.Adhes" user "F.Adhesive")
		(11 "B.Adhes" user "B.Adhesive")
		(13 "F.Paste" user "Package Geometry/Pastemask Top")
		(15 "B.Paste" user "Package Geometry/Pastemask Bottom")
		(5 "F.SilkS" user "Ref Des/Silkscreen Top")
		(7 "B.SilkS" user "Ref Des/Silkscreen Bottom")
		(1 "F.Mask" user "Board Geometry/Soldermask Top")
		(3 "B.Mask" user "Board Geometry/Soldermask Bottom")
		(17 "Dwgs.User" user "User.Drawings")
		(19 "Cmts.User" user "User.Comments")
		(21 "Eco1.User" user "User.Eco1")
		(23 "Eco2.User" user "User.Eco2")
		(25 "Edge.Cuts" user "Board Geometry/Outline")
		(27 "Margin" user)
		(31 "F.CrtYd" user "Package Geometry/Place Bound Top")
		(29 "B.CrtYd" user "Package Geometry/Place Bound Bottom")
		(35 "F.Fab" user "Ref Des/Assembly Top")
		(33 "B.Fab" user "Ref Des/Assembly Bottom")
	)
	(footprint ""
		(layer "F.Cu")
		(at 36.399978 -25.619964)
		(property "Reference" "J8"
			(at -1.779778 -8.338566 0)
			(unlocked yes)
			(layer "F.SilkS")
			(effects
				(font
					(size 0.7874 0.5842)
					(thickness 0.1524)
				)
				(justify left)
			)
		)
		(property "Value" ""
			(at 0 0 0)
			(layer "F.Fab")
			(effects
				(font
					(size 1.27 1.27)
				)
			)
		)
		(duplicate_pad_numbers_are_jumpers no)
		(fp_line
			(start -1.450086 -7.549896)
			(end -1.450086 -6.4516)
			(stroke
				(width 0.1524)
				(type default)
			)
			(layer "F.SilkS")
		)
		(fp_line
			(start -1.450086 6.4516)
			(end -1.450086 7.549896)
			(stroke
				(width 0.1524)
				(type default)
			)
			(layer "F.SilkS")
		)
		(fp_line
			(start -1.450086 7.549896)
			(end -0.2794 7.549896)
			(stroke
				(width 0.1524)
				(type default)
			)
			(layer "F.SilkS")
		)
		(fp_line
			(start -0.2794 -7.549896)
			(end -1.450086 -7.549896)
			(stroke
				(width 0.1524)
				(type default)
			)
			(layer "F.SilkS")
		)
		(fp_line
			(start 1.450086 6.5532)
			(end 1.450086 -6.5532)
			(stroke
				(width 0.1524)
				(type default)
			)
			(layer "F.SilkS")
		)
		(fp_poly
			(pts
				(xy -3.7084 -5.491988) (xy -3.7084 -6.507988) (xy -2.6924 -5.999988)
			)
			(stroke
				(width 0)
				(type default)
			)
			(fill yes)
			(layer "F.SilkS")
		)
		(fp_line
			(start -1.450086 -7.549896)
			(end -1.450086 7.549896)
			(stroke
				(width 0.1)
				(type default)
			)
			(layer "F.Fab")
		)
		(fp_line
			(start -1.450086 7.549896)
			(end 1.450086 7.549896)
			(stroke
				(width 0.1)
				(type default)
			)
			(layer "F.Fab")
		)
		(fp_line
			(start 1.450086 -7.549896)
			(end -1.450086 -7.549896)
			(stroke
				(width 0.1)
				(type default)
			)
			(layer "F.Fab")
		)
		(fp_line
			(start 1.450086 7.549896)
			(end 1.450086 -7.549896)
			(stroke
				(width 0.1)
				(type default)
			)
			(layer "F.Fab")
		)
		(fp_poly
			(pts
				(xy -3.7084 -5.491988) (xy -3.7084 -6.507988) (xy -2.6924 -5.999988)
			)
			(stroke
				(width 0)
				(type default)
			)
			(fill yes)
			(layer "F.Fab")
		)
		(fp_text user "13"
			(at -3.235452 5.9944 270)
			(unlocked yes)
			(layer "F.SilkS")
			(effects
				(font
					(size 0.7874 0.5842)
					(thickness 0.1524)
				)
			)
		)
		(fp_text user "13"
			(at -3.235452 5.9944 270)
			(unlocked yes)
			(layer "F.Fab")
			(effects
				(font
					(size 0.7874 0.5842)
					(thickness 0.1524)
				)
			)
		)
		(pad "1" smd rect
			(at -1.774952 -5.999988 270)
			(size 0.6096 1.5494)
			(layers "F.Cu" "F.Mask" "F.Paste")
			(net "V_DACR_IO")
		)
		(pad "2" smd rect
			(at -1.774952 -4.99999 270)
			(size 0.6096 1.5494)
			(layers "F.Cu" "F.Mask" "F.Paste")
			(net "GND")
		)
		(pad "3" smd rect
			(at -1.774952 -3.999992 270)
			(size 0.6096 1.5494)
			(layers "F.Cu" "F.Mask" "F.Paste")
			(net "V_DACG_IO")
		)
		(pad "4" smd rect
			(at -1.774952 -2.999994 270)
			(size 0.6096 1.5494)
			(layers "F.Cu" "F.Mask" "F.Paste")
			(net "GND")
		)
		(pad "5" smd rect
			(at -1.774952 -1.999996 270)
			(size 0.6096 1.5494)
			(layers "F.Cu" "F.Mask" "F.Paste")
			(net "V_DACB_IO")
		)
		(pad "6" smd rect
			(at -1.774952 -0.999998 270)
			(size 0.6096 1.5494)
			(layers "F.Cu" "F.Mask" "F.Paste")
			(net "GND")
		)
		(pad "7" smd rect
			(at -1.774952 0 270)
			(size 0.6096 1.5494)
			(layers "F.Cu" "F.Mask" "F.Paste")
			(net "V_VGAVS_BUF")
		)
		(pad "8" smd rect
			(at -1.774952 0.999998 270)
			(size 0.6096 1.5494)
			(layers "F.Cu" "F.Mask" "F.Paste")
			(net "GND")
		)
		(pad "9" smd rect
			(at -1.774952 1.999996 270)
			(size 0.6096 1.5494)
			(layers "F.Cu" "F.Mask" "F.Paste")
			(net "V_VGAHS_BUF")
		)
		(pad "10" smd rect
			(at -1.774952 2.999994 270)
			(size 0.6096 1.5494)
			(layers "F.Cu" "F.Mask" "F.Paste")
			(net "GND")
		)
		(pad "11" smd rect
			(at -1.774952 3.999992 270)
			(size 0.6096 1.5494)
			(layers "F.Cu" "F.Mask" "F.Paste")
			(net "V_BMC_LS_DDC_SDA_R")
		)
		(pad "12" smd rect
			(at -1.774952 4.99999 270)
			(size 0.6096 1.5494)
			(layers "F.Cu" "F.Mask" "F.Paste")
			(net "V_BMC_LS_DDC_SCL_R")
		)
		(pad "13" smd rect
			(at -1.774952 5.999988 270)
			(size 0.6096 1.5494)
			(layers "F.Cu" "F.Mask" "F.Paste")
			(net "CRT_VCC5_2_FUSE")
		)
		(pad "G1" smd rect
			(at 0.750062 -7.29996 270)
			(size 1.2192 1.8034)
			(layers "F.Cu" "F.Mask" "F.Paste")
			(net "GND")
		)
		(pad "G2" smd rect
			(at 0.750062 7.29996 270)
			(size 1.2192 1.8034)
			(layers "F.Cu" "F.Mask" "F.Paste")
			(net "GND")
		)
	)
	(footprint ""
		(layer "F.Cu")
		(at 73.980294 -98.425 180)
		(property "Reference" "R47"
			(at 0 0 180)
			(layer "F.SilkS")
			(hide yes)
			(effects
				(font
					(size 1.27 1.27)
				)
			)
		)
		(property "Value" ""
			(at 0 0 180)
			(layer "F.Fab")
			(effects
				(font
					(size 1.27 1.27)
				)
			)
		)
		(duplicate_pad_numbers_are_jumpers no)
		(fp_line
			(start 0.7874 0.4064)
			(end -0.7874 0.4064)
			(stroke
				(width 0.1524)
				(type default)
			)
			(layer "F.SilkS")
		)
		(fp_line
			(start 0.7874 -0.4064)
			(end 0.7874 0.4064)
			(stroke
				(width 0.1524)
				(type default)
			)
			(layer "F.SilkS")
		)
		(fp_line
			(start -0.7874 0.4064)
			(end -0.7874 -0.4064)
			(stroke
				(width 0.1524)
				(type default)
			)
			(layer "F.SilkS")
		)
		(fp_line
			(start -0.7874 -0.4064)
			(end 0.7874 -0.4064)
			(stroke
				(width 0.1524)
				(type default)
			)
			(layer "F.SilkS")
		)
		(fp_line
			(start 0.67945 0.3048)
			(end 0.120396 0.3048)
			(stroke
				(width 0.1)
				(type default)
			)
			(layer "F.Fab")
		)
		(fp_line
			(start 0.67945 -0.3048)
			(end 0.67945 0.3048)
			(stroke
				(width 0.1)
				(type default)
			)
			(layer "F.Fab")
		)
		(fp_line
			(start 0.12065 -0.2794)
			(end 0.12065 -0.3048)
			(stroke
				(width 0.1)
				(type default)
			)
			(layer "F.Fab")
		)
		(fp_line
			(start 0.12065 -0.3048)
			(end 0.67945 -0.3048)
			(stroke
				(width 0.1)
				(type default)
			)
			(layer "F.Fab")
		)
		(fp_line
			(start 0.120396 0.3048)
			(end 0.120396 0.2794)
			(stroke
				(width 0.1)
				(type default)
			)
			(layer "F.Fab")
		)
		(fp_line
			(start 0.120396 0.2794)
			(end -0.12065 0.2794)
			(stroke
				(width 0.1)
				(type default)
			)
			(layer "F.Fab")
		)
		(fp_line
			(start -0.12065 0.3048)
			(end -0.67945 0.3048)
			(stroke
				(width 0.1)
				(type default)
			)
			(layer "F.Fab")
		)
		(fp_line
			(start -0.12065 0.2794)
			(end -0.12065 0.3048)
			(stroke
				(width 0.1)
				(type default)
			)
			(layer "F.Fab")
		)
		(fp_line
			(start -0.12065 -0.2794)
			(end 0.12065 -0.2794)
			(stroke
				(width 0.1)
				(type default)
			)
			(layer "F.Fab")
		)
		(fp_line
			(start -0.12065 -0.305054)
			(end -0.12065 -0.2794)
			(stroke
				(width 0.1)
				(type default)
			)
			(layer "F.Fab")
		)
		(fp_line
			(start -0.67945 0.3048)
			(end -0.67945 -0.305054)
			(stroke
				(width 0.1)
				(type default)
			)
			(layer "F.Fab")
		)
		(fp_line
			(start -0.67945 -0.305054)
			(end -0.12065 -0.305054)
			(stroke
				(width 0.1)
				(type default)
			)
			(layer "F.Fab")
		)
		(pad "1" smd circle
			(at -0.40005 0 180)
			(size 0 0)
			(layers "F.Cu" "F.Mask" "F.Paste")
			(net "SMB_BMC_TPM_MM16_SCL")
		)
		(pad "2" smd circle
			(at 0.40005 0 180)
			(size 0 0)
			(layers "F.Cu" "F.Mask" "F.Paste")
			(net "SMB_BMC_MM16_R5_SCL")
		)
	)
)
